(kicad_pcb
	(version 20260206)
	(generator "pcbnew")
	(generator_version "10.0")
	(general
		(thickness 1.6)
		(legacy_teardrops no)
	)
	(paper "A4")
	(title_block
		(title "panther-plus-userver — 13130-1b_20150205.brd")
		(comment 1 "Honey Badger (Wiwynn) / footprint 1 of 1509 (GF1), pads 1-110 of 164")
	)
	(layers
		(0 "F.Cu" signal "TOP")
		(4 "In1.Cu" signal "L2")
		(6 "In2.Cu" signal "L3")
		(8 "In3.Cu" signal "L4")
		(10 "In4.Cu" signal "L5")
		(12 "In5.Cu" signal "L6")
		(14 "In6.Cu" signal "L7")
		(16 "In7.Cu" signal "L8")
		(18 "In8.Cu" signal "L9")
		(20 "In9.Cu" signal "L10")
		(22 "In10.Cu" signal "L11")
		(2 "B.Cu" signal "BOTTOM")
		(9 "F.Adhes" user "F.Adhesive")
		(11 "B.Adhes" user "B.Adhesive")
		(13 "F.Paste" user "Package Geometry/Pastemask Top")
		(15 "B.Paste" user "Package Geometry/Pastemask Bottom")
		(5 "F.SilkS" user "Ref Des/Silkscreen Top")
		(7 "B.SilkS" user "Ref Des/Silkscreen Bottom")
		(1 "F.Mask" user "Board Geometry/Soldermask Top")
		(3 "B.Mask" user "Board Geometry/Soldermask Bottom")
		(17 "Dwgs.User" user "User.Drawings")
		(19 "Cmts.User" user "User.Comments")
		(21 "Eco1.User" user "User.Eco1")
		(23 "Eco2.User" user "User.Eco2")
		(25 "Edge.Cuts" user "Board Geometry/Outline")
		(27 "Margin" user)
		(31 "F.CrtYd" user "Package Geometry/Place Bound Top")
		(29 "B.CrtYd" user "Package Geometry/Place Bound Bottom")
		(35 "F.Fab" user "Ref Des/Assembly Top")
		(33 "B.Fab" user "Ref Des/Assembly Bottom")
	)
	(footprint ""
		(layer "F.Cu")
		(at 86.849966 -4.100068)
		(property "Reference" "GF1"
			(at 0 0 0)
			(layer "F.SilkS")
			(hide yes)
			(effects
				(font
					(size 1.27 1.27)
				)
			)
		)
		(property "Value" "GF-PCIE-164P-15-GP"
			(at 15.2654 -6.2992 0)
			(unlocked yes)
			(layer "F.Fab")
			(hide yes)
			(effects
				(font
					(size 1.016 1.016)
					(thickness 0.1524)
				)
			)
		)
		(property "Device Type" "GF-PCIE-164P-15"
			(at 15.2654 -7.8232 0)
			(unlocked yes)
			(layer "F.Fab")
			(hide yes)
			(effects
				(font
					(size 1.016 1.016)
					(thickness 0.1524)
				)
			)
		)
		(duplicate_pad_numbers_are_jumpers no)
		(pad "A1" smd rect
			(at 11.500104 -2.5908)
			(size 0.7112 3.2004)
			(layers "F.Cu" "F.Mask" "F.Paste")
			(net "BOARD_PRSNT#")
		)
		(pad "A2" smd rect
			(at 10.500106 -2.0955)
			(size 0.7112 4.191)
			(layers "F.Cu" "F.Mask" "F.Paste")
			(net "P12V")
		)
		(pad "A3" smd rect
			(at 9.500108 -2.0955)
			(size 0.7112 4.191)
			(layers "F.Cu" "F.Mask" "F.Paste")
			(net "P12V")
		)
		(pad "A4" smd rect
			(at 8.50011 -2.0955)
			(size 0.7112 4.191)
			(layers "F.Cu" "F.Mask" "F.Paste")
			(net "GND")
		)
		(pad "A5" smd rect
			(at 7.500112 -2.0955)
			(size 0.7112 4.191)
			(layers "F.Cu" "F.Mask" "F.Paste")
			(net "SLOT_ID0")
		)
		(pad "A6" smd rect
			(at 6.500114 -2.0955)
			(size 0.7112 4.191)
			(layers "F.Cu" "F.Mask" "F.Paste")
			(net "SLOT_ID1")
		)
		(pad "A7" smd rect
			(at 5.500116 -2.0955)
			(size 0.7112 4.191)
			(layers "F.Cu" "F.Mask" "F.Paste")
			(net "GF_CPU_TXD")
		)
		(pad "A8" smd rect
			(at 4.500118 -2.0955)
			(size 0.7112 4.191)
			(layers "F.Cu" "F.Mask" "F.Paste")
			(net "GF_CPU_RXD")
		)
		(pad "A9" smd rect
			(at 3.50012 -2.0955)
			(size 0.7112 4.191)
			(layers "F.Cu" "F.Mask" "F.Paste")
			(net "SLOT_ID2")
		)
		(pad "A10" smd rect
			(at 2.500122 -2.0955)
			(size 0.7112 4.191)
			(layers "F.Cu" "F.Mask" "F.Paste")
			(net "SLOT_ID3")
		)
		(pad "A11" smd rect
			(at 1.500124 -2.0955)
			(size 0.7112 4.191)
			(layers "F.Cu" "F.Mask" "F.Paste")
			(net "PCIE_RESET#")
		)
		(pad "A12" smd rect
			(at -1.500124 -2.0955)
			(size 0.7112 4.191)
			(layers "F.Cu" "F.Mask" "F.Paste")
			(net "GND")
		)
		(pad "A13" smd rect
			(at -2.500122 -2.0955)
			(size 0.7112 4.191)
			(layers "F.Cu" "F.Mask" "F.Paste")
			(net "CLK_100M_PCIE_SAS_DP")
		)
		(pad "A14" smd rect
			(at -3.50012 -2.0955)
			(size 0.7112 4.191)
			(layers "F.Cu" "F.Mask" "F.Paste")
			(net "CLK_100M_PCIE_SAS_DN")
		)
		(pad "A15" smd rect
			(at -4.500118 -2.0955)
			(size 0.7112 4.191)
			(layers "F.Cu" "F.Mask" "F.Paste")
			(net "GND")
		)
		(pad "A16" smd rect
			(at -5.500116 -2.0955)
			(size 0.7112 4.191)
			(layers "F.Cu" "F.Mask" "F.Paste")
			(net "GND")
		)
		(pad "A17" smd rect
			(at -6.500114 -2.0955)
			(size 0.7112 4.191)
			(layers "F.Cu" "F.Mask" "F.Paste")
			(net "P2E_CPU_SAS_RX_DP0")
		)
		(pad "A18" smd rect
			(at -7.500112 -2.0955)
			(size 0.7112 4.191)
			(layers "F.Cu" "F.Mask" "F.Paste")
			(net "P2E_CPU_SAS_RX_DN0")
		)
		(pad "A19" smd rect
			(at -8.50011 -2.0955)
			(size 0.7112 4.191)
			(layers "F.Cu" "F.Mask" "F.Paste")
			(net "GND")
		)
		(pad "A20" smd rect
			(at -9.500108 -2.0955)
			(size 0.7112 4.191)
			(layers "F.Cu" "F.Mask" "F.Paste")
			(net "GND")
		)
		(pad "A21" smd rect
			(at -10.500106 -2.0955)
			(size 0.7112 4.191)
			(layers "F.Cu" "F.Mask" "F.Paste")
			(net "P2E_CPU_SAS_RX_DP1")
		)
		(pad "A22" smd rect
			(at -11.500104 -2.0955)
			(size 0.7112 4.191)
			(layers "F.Cu" "F.Mask" "F.Paste")
			(net "P2E_CPU_SAS_RX_DN1")
		)
		(pad "A23" smd rect
			(at -12.500102 -2.0955)
			(size 0.7112 4.191)
			(layers "F.Cu" "F.Mask" "F.Paste")
			(net "GND")
		)
		(pad "A24" smd rect
			(at -13.5001 -2.0955)
			(size 0.7112 4.191)
			(layers "F.Cu" "F.Mask" "F.Paste")
			(net "GND")
		)
		(pad "A25" smd rect
			(at -14.500098 -2.0955)
			(size 0.7112 4.191)
			(layers "F.Cu" "F.Mask" "F.Paste")
			(net "P2E_CPU_SAS_RX_DP2")
		)
		(pad "A26" smd rect
			(at -15.500096 -2.0955)
			(size 0.7112 4.191)
			(layers "F.Cu" "F.Mask" "F.Paste")
			(net "P2E_CPU_SAS_RX_DN2")
		)
		(pad "A27" smd rect
			(at -16.500094 -2.0955)
			(size 0.7112 4.191)
			(layers "F.Cu" "F.Mask" "F.Paste")
			(net "GND")
		)
		(pad "A28" smd rect
			(at -17.500092 -2.0955)
			(size 0.7112 4.191)
			(layers "F.Cu" "F.Mask" "F.Paste")
			(net "GND")
		)
		(pad "A29" smd rect
			(at -18.50009 -2.0955)
			(size 0.7112 4.191)
			(layers "F.Cu" "F.Mask" "F.Paste")
			(net "P2E_CPU_SAS_RX_DP3")
		)
		(pad "A30" smd rect
			(at -19.500088 -2.0955)
			(size 0.7112 4.191)
			(layers "F.Cu" "F.Mask" "F.Paste")
			(net "P2E_CPU_SAS_RX_DN3")
		)
		(pad "A31" smd rect
			(at -20.500086 -2.0955)
			(size 0.7112 4.191)
			(layers "F.Cu" "F.Mask" "F.Paste")
			(net "GND")
		)
		(pad "A32" smd rect
			(at -21.500084 -2.0955)
			(size 0.7112 4.191)
			(layers "F.Cu" "F.Mask" "F.Paste")
			(net "GND")
		)
		(pad "A33" smd rect
			(at -22.500082 -2.0955)
			(size 0.7112 4.191)
			(layers "F.Cu" "F.Mask" "F.Paste")
			(net "SATA2_RX_C_DP0")
		)
		(pad "A34" smd rect
			(at -23.50008 -2.0955)
			(size 0.7112 4.191)
			(layers "F.Cu" "F.Mask" "F.Paste")
			(net "SATA2_RX_C_DN0")
		)
		(pad "A35" smd rect
			(at -24.500078 -2.0955)
			(size 0.7112 4.191)
			(layers "F.Cu" "F.Mask" "F.Paste")
			(net "GND")
		)
		(pad "A36" smd rect
			(at -25.500076 -2.0955)
			(size 0.7112 4.191)
			(layers "F.Cu" "F.Mask" "F.Paste")
			(net "GND")
		)
		(pad "A37" smd rect
			(at -26.500074 -2.0955)
			(size 0.7112 4.191)
			(layers "F.Cu" "F.Mask" "F.Paste")
			(net "CLK_100M_PCIE2_REFCLK_DP")
		)
		(pad "A38" smd rect
			(at -27.500072 -2.0955)
			(size 0.7112 4.191)
			(layers "F.Cu" "F.Mask" "F.Paste")
			(net "CLK_100M_PCIE2_REFCLK_DN")
		)
		(pad "A39" smd rect
			(at -28.50007 -2.0955)
			(size 0.7112 4.191)
			(layers "F.Cu" "F.Mask" "F.Paste")
			(net "GND")
		)
		(pad "A40" smd rect
			(at -29.500068 -2.0955)
			(size 0.7112 4.191)
			(layers "F.Cu" "F.Mask" "F.Paste")
			(net "GND")
		)
		(pad "A41" smd rect
			(at -30.500066 -2.0955)
			(size 0.7112 4.191)
			(layers "F.Cu" "F.Mask" "F.Paste")
			(net "PCIE_RSVD_A41")
		)
		(pad "A42" smd rect
			(at -31.500064 -2.0955)
			(size 0.7112 4.191)
			(layers "F.Cu" "F.Mask" "F.Paste")
			(net "GBE_R_SMBALRT#")
		)
		(pad "A43" smd rect
			(at -32.500062 -2.0955)
			(size 0.7112 4.191)
			(layers "F.Cu" "F.Mask" "F.Paste")
			(net "GND")
		)
		(pad "A44" smd rect
			(at -33.50006 -2.0955)
			(size 0.7112 4.191)
			(layers "F.Cu" "F.Mask" "F.Paste")
			(net "GND")
		)
		(pad "A45" smd rect
			(at -34.500058 -2.0955)
			(size 0.7112 4.191)
			(layers "F.Cu" "F.Mask" "F.Paste")
			(net "CPU_GBE_RX_C_DP0")
		)
		(pad "A46" smd rect
			(at -35.500056 -2.0955)
			(size 0.7112 4.191)
			(layers "F.Cu" "F.Mask" "F.Paste")
			(net "CPU_GBE_RX_C_DN0")
		)
		(pad "A47" smd rect
			(at -36.500054 -2.0955)
			(size 0.7112 4.191)
			(layers "F.Cu" "F.Mask" "F.Paste")
			(net "GND")
		)
		(pad "A48" smd rect
			(at -37.500052 -2.0955)
			(size 0.7112 4.191)
			(layers "F.Cu" "F.Mask" "F.Paste")
			(net "GND")
		)
		(pad "A49" smd rect
			(at -38.50005 -2.0955)
			(size 0.7112 4.191)
			(layers "F.Cu" "F.Mask" "F.Paste")
			(net "P2E_CPU_SAS_RX_DP4")
		)
		(pad "A50" smd rect
			(at -39.500048 -2.0955)
			(size 0.7112 4.191)
			(layers "F.Cu" "F.Mask" "F.Paste")
			(net "P2E_CPU_SAS_RX_DN4")
		)
		(pad "A51" smd rect
			(at -40.500046 -2.0955)
			(size 0.7112 4.191)
			(layers "F.Cu" "F.Mask" "F.Paste")
			(net "GND")
		)
		(pad "A52" smd rect
			(at -41.500044 -2.0955)
			(size 0.7112 4.191)
			(layers "F.Cu" "F.Mask" "F.Paste")
			(net "GND")
		)
		(pad "A53" smd rect
			(at -42.500042 -2.0955)
			(size 0.7112 4.191)
			(layers "F.Cu" "F.Mask" "F.Paste")
			(net "P2E_CPU_SAS_RX_DP5")
		)
		(pad "A54" smd rect
			(at -43.50004 -2.0955)
			(size 0.7112 4.191)
			(layers "F.Cu" "F.Mask" "F.Paste")
			(net "P2E_CPU_SAS_RX_DN5")
		)
		(pad "A55" smd rect
			(at -44.500038 -2.0955)
			(size 0.7112 4.191)
			(layers "F.Cu" "F.Mask" "F.Paste")
			(net "GND")
		)
		(pad "A56" smd rect
			(at -45.500036 -2.0955)
			(size 0.7112 4.191)
			(layers "F.Cu" "F.Mask" "F.Paste")
			(net "GND")
		)
		(pad "A57" smd rect
			(at -46.500034 -2.0955)
			(size 0.7112 4.191)
			(layers "F.Cu" "F.Mask" "F.Paste")
			(net "P2E_CPU_SAS_RX_DP6")
		)
		(pad "A58" smd rect
			(at -47.500032 -2.0955)
			(size 0.7112 4.191)
			(layers "F.Cu" "F.Mask" "F.Paste")
			(net "P2E_CPU_SAS_RX_DN6")
		)
		(pad "A59" smd rect
			(at -48.50003 -2.0955)
			(size 0.7112 4.191)
			(layers "F.Cu" "F.Mask" "F.Paste")
			(net "GND")
		)
		(pad "A60" smd rect
			(at -49.500028 -2.0955)
			(size 0.7112 4.191)
			(layers "F.Cu" "F.Mask" "F.Paste")
			(net "GND")
		)
		(pad "A61" smd rect
			(at -50.500026 -2.0955)
			(size 0.7112 4.191)
			(layers "F.Cu" "F.Mask" "F.Paste")
			(net "P2E_CPU_SAS_RX_DP7")
		)
		(pad "A62" smd rect
			(at -51.500024 -2.0955)
			(size 0.7112 4.191)
			(layers "F.Cu" "F.Mask" "F.Paste")
			(net "P2E_CPU_SAS_RX_DN7")
		)
		(pad "A63" smd rect
			(at -52.500022 -2.0955)
			(size 0.7112 4.191)
			(layers "F.Cu" "F.Mask" "F.Paste")
			(net "GND")
		)
		(pad "A64" smd rect
			(at -53.50002 -2.0955)
			(size 0.7112 4.191)
			(layers "F.Cu" "F.Mask" "F.Paste")
			(net "GND")
		)
		(pad "A65" smd rect
			(at -54.500018 -2.0955)
			(size 0.7112 4.191)
			(layers "F.Cu" "F.Mask" "F.Paste")
			(net "P2E_CPU_ETH10G_RX_DP8")
		)
		(pad "A66" smd rect
			(at -55.500016 -2.0955)
			(size 0.7112 4.191)
			(layers "F.Cu" "F.Mask" "F.Paste")
			(net "P2E_CPU_ETH10G_RX_DN8")
		)
		(pad "A67" smd rect
			(at -56.500014 -2.0955)
			(size 0.7112 4.191)
			(layers "F.Cu" "F.Mask" "F.Paste")
			(net "GND")
		)
		(pad "A68" smd rect
			(at -57.500012 -2.0955)
			(size 0.7112 4.191)
			(layers "F.Cu" "F.Mask" "F.Paste")
			(net "GND")
		)
		(pad "A69" smd rect
			(at -58.50001 -2.0955)
			(size 0.7112 4.191)
			(layers "F.Cu" "F.Mask" "F.Paste")
			(net "P2E_CPU_ETH10G_RX_DP9")
		)
		(pad "A70" smd rect
			(at -59.500008 -2.0955)
			(size 0.7112 4.191)
			(layers "F.Cu" "F.Mask" "F.Paste")
			(net "P2E_CPU_ETH10G_RX_DN9")
		)
		(pad "A71" smd rect
			(at -60.500006 -2.0955)
			(size 0.7112 4.191)
			(layers "F.Cu" "F.Mask" "F.Paste")
			(net "GND")
		)
		(pad "A72" smd rect
			(at -61.500004 -2.0955)
			(size 0.7112 4.191)
			(layers "F.Cu" "F.Mask" "F.Paste")
			(net "GND")
		)
		(pad "A73" smd rect
			(at -62.500002 -2.0955)
			(size 0.7112 4.191)
			(layers "F.Cu" "F.Mask" "F.Paste")
			(net "P2E_CPU_ETH10G_RX_DP10")
		)
		(pad "A74" smd rect
			(at -63.5 -2.0955)
			(size 0.7112 4.191)
			(layers "F.Cu" "F.Mask" "F.Paste")
			(net "P2E_CPU_ETH10G_RX_DN10")
		)
		(pad "A75" smd rect
			(at -64.499998 -2.0955)
			(size 0.7112 4.191)
			(layers "F.Cu" "F.Mask" "F.Paste")
			(net "GND")
		)
		(pad "A76" smd rect
			(at -65.499996 -2.0955)
			(size 0.7112 4.191)
			(layers "F.Cu" "F.Mask" "F.Paste")
			(net "GND")
		)
		(pad "A77" smd rect
			(at -66.499994 -2.0955)
			(size 0.7112 4.191)
			(layers "F.Cu" "F.Mask" "F.Paste")
			(net "P2E_CPU_ETH10G_RX_DP11")
		)
		(pad "A78" smd rect
			(at -67.499992 -2.0955)
			(size 0.7112 4.191)
			(layers "F.Cu" "F.Mask" "F.Paste")
			(net "P2E_CPU_ETH10G_RX_DN11")
		)
		(pad "A79" smd rect
			(at -68.49999 -2.0955)
			(size 0.7112 4.191)
			(layers "F.Cu" "F.Mask" "F.Paste")
			(net "GND")
		)
		(pad "A80" smd rect
			(at -69.499988 -2.0955)
			(size 0.7112 4.191)
			(layers "F.Cu" "F.Mask" "F.Paste")
			(net "GND")
		)
		(pad "A81" smd rect
			(at -70.499986 -2.0955)
			(size 0.7112 4.191)
			(layers "F.Cu" "F.Mask" "F.Paste")
			(net "P12V")
		)
		(pad "A82" smd rect
			(at -71.499984 -2.0955)
			(size 0.7112 4.191)
			(layers "F.Cu" "F.Mask" "F.Paste")
			(net "P12V")
		)
		(pad "B1" smd rect
			(at 11.500104 -1.7145)
			(size 0.7112 4.191)
			(drill
				(offset 0 -0.381)
			)
			(layers "F.Cu" "F.Mask" "F.Paste")
			(net "P12V")
		)
		(pad "B2" smd rect
			(at 10.500106 -1.7145)
			(size 0.7112 4.191)
			(drill
				(offset 0 -0.381)
			)
			(layers "F.Cu" "F.Mask" "F.Paste")
			(net "P12V")
		)
		(pad "B3" smd rect
			(at 9.500108 -1.7145)
			(size 0.7112 4.191)
			(drill
				(offset 0 -0.381)
			)
			(layers "F.Cu" "F.Mask" "F.Paste")
			(net "P12V")
		)
		(pad "B4" smd rect
			(at 8.50011 -1.7145)
			(size 0.7112 4.191)
			(drill
				(offset 0 -0.381)
			)
			(layers "F.Cu" "F.Mask" "F.Paste")
			(net "GND")
		)
		(pad "B5" smd rect
			(at 7.500112 -1.7145)
			(size 0.7112 4.191)
			(drill
				(offset 0 -0.381)
			)
			(layers "F.Cu" "F.Mask" "F.Paste")
			(net "PCIE_GF_I2C_CLK")
		)
		(pad "B6" smd rect
			(at 6.500114 -1.7145)
			(size 0.7112 4.191)
			(drill
				(offset 0 -0.381)
			)
			(layers "F.Cu" "F.Mask" "F.Paste")
			(net "PCIE_GF_I2C_DATA")
		)
		(pad "B7" smd rect
			(at 5.500116 -1.7145)
			(size 0.7112 4.191)
			(drill
				(offset 0 -0.381)
			)
			(layers "F.Cu" "F.Mask" "F.Paste")
			(net "GND")
		)
		(pad "B8" smd rect
			(at 4.500118 -1.7145)
			(size 0.7112 4.191)
			(drill
				(offset 0 -0.381)
			)
			(layers "F.Cu" "F.Mask" "F.Paste")
			(net "PWR_BTN#")
		)
		(pad "B9" smd rect
			(at 3.50012 -1.7145)
			(size 0.7112 4.191)
			(drill
				(offset 0 -0.381)
			)
			(layers "F.Cu" "F.Mask" "F.Paste")
			(net "USB_P1_DP")
		)
		(pad "B10" smd rect
			(at 2.500122 -1.7145)
			(size 0.7112 4.191)
			(drill
				(offset 0 -0.381)
			)
			(layers "F.Cu" "F.Mask" "F.Paste")
			(net "USB_P1_DN")
		)
		(pad "B11" smd rect
			(at 1.500124 -1.7145)
			(size 0.7112 4.191)
			(drill
				(offset 0 -0.381)
			)
			(layers "F.Cu" "F.Mask" "F.Paste")
			(net "BMC_SYS_RESET#")
		)
		(pad "B12" smd rect
			(at -1.500124 -1.7145)
			(size 0.7112 4.191)
			(drill
				(offset 0 -0.381)
			)
			(layers "F.Cu" "F.Mask" "F.Paste")
			(net "PCIE_GF_I2C_R_ALERT#")
		)
		(pad "B13" smd rect
			(at -2.500122 -1.7145)
			(size 0.7112 4.191)
			(drill
				(offset 0 -0.381)
			)
			(layers "F.Cu" "F.Mask" "F.Paste")
			(net "GND")
		)
		(pad "B14" smd rect
			(at -3.50012 -1.7145)
			(size 0.7112 4.191)
			(drill
				(offset 0 -0.381)
			)
			(layers "F.Cu" "F.Mask" "F.Paste")
			(net "GND")
		)
		(pad "B15" smd rect
			(at -4.500118 -1.7145)
			(size 0.7112 4.191)
			(drill
				(offset 0 -0.381)
			)
			(layers "F.Cu" "F.Mask" "F.Paste")
			(net "P2E_CPU_SAS_TX_DP0")
		)
		(pad "B16" smd rect
			(at -5.500116 -1.7145)
			(size 0.7112 4.191)
			(drill
				(offset 0 -0.381)
			)
			(layers "F.Cu" "F.Mask" "F.Paste")
			(net "P2E_CPU_SAS_TX_DN0")
		)
		(pad "B17" smd rect
			(at -6.500114 -1.7145)
			(size 0.7112 4.191)
			(drill
				(offset 0 -0.381)
			)
			(layers "F.Cu" "F.Mask" "F.Paste")
			(net "GND")
		)
		(pad "B18" smd rect
			(at -7.500112 -1.7145)
			(size 0.7112 4.191)
			(drill
				(offset 0 -0.381)
			)
			(layers "F.Cu" "F.Mask" "F.Paste")
			(net "GND")
		)
		(pad "B19" smd rect
			(at -8.50011 -1.7145)
			(size 0.7112 4.191)
			(drill
				(offset 0 -0.381)
			)
			(layers "F.Cu" "F.Mask" "F.Paste")
			(net "P2E_CPU_SAS_TX_DP1")
		)
		(pad "B20" smd rect
			(at -9.500108 -1.7145)
			(size 0.7112 4.191)
			(drill
				(offset 0 -0.381)
			)
			(layers "F.Cu" "F.Mask" "F.Paste")
			(net "P2E_CPU_SAS_TX_DN1")
		)
		(pad "B21" smd rect
			(at -10.500106 -1.7145)
			(size 0.7112 4.191)
			(drill
				(offset 0 -0.381)
			)
			(layers "F.Cu" "F.Mask" "F.Paste")
			(net "GND")
		)
		(pad "B22" smd rect
			(at -11.500104 -1.7145)
			(size 0.7112 4.191)
			(drill
				(offset 0 -0.381)
			)
			(layers "F.Cu" "F.Mask" "F.Paste")
			(net "GND")
		)
		(pad "B23" smd rect
			(at -12.500102 -1.7145)
			(size 0.7112 4.191)
			(drill
				(offset 0 -0.381)
			)
			(layers "F.Cu" "F.Mask" "F.Paste")
			(net "P2E_CPU_SAS_TX_DP2")
		)
		(pad "B24" smd rect
			(at -13.5001 -1.7145)
			(size 0.7112 4.191)
			(drill
				(offset 0 -0.381)
			)
			(layers "F.Cu" "F.Mask" "F.Paste")
			(net "P2E_CPU_SAS_TX_DN2")
		)
		(pad "B25" smd rect
			(at -14.500098 -1.7145)
			(size 0.7112 4.191)
			(drill
				(offset 0 -0.381)
			)
			(layers "F.Cu" "F.Mask" "F.Paste")
			(net "GND")
		)
		(pad "B26" smd rect
			(at -15.500096 -1.7145)
			(size 0.7112 4.191)
			(drill
				(offset 0 -0.381)
			)
			(layers "F.Cu" "F.Mask" "F.Paste")
			(net "GND")
		)
		(pad "B27" smd rect
			(at -16.500094 -1.7145)
			(size 0.7112 4.191)
			(drill
				(offset 0 -0.381)
			)
			(layers "F.Cu" "F.Mask" "F.Paste")
			(net "P2E_CPU_SAS_TX_DP3")
		)
		(pad "B28" smd rect
			(at -17.500092 -1.7145)
			(size 0.7112 4.191)
			(drill
				(offset 0 -0.381)
			)
			(layers "F.Cu" "F.Mask" "F.Paste")
			(net "P2E_CPU_SAS_TX_DN3")
		)
	)
)
